(kicad_pcb
	(version 20260206)
	(generator "pcbnew")
	(generator_version "10.0")
	(general
		(thickness 1.6)
		(legacy_teardrops no)
	)
	(paper "A4")
	(title_block
		(title "Bryce Canyon_SCC_16316-1_OCP.brd")
		(comment 1 "Bryce Canyon / footprints 1424-1431 of 1561")
	)
	(layers
		(0 "F.Cu" signal "TOP")
		(4 "In1.Cu" signal "L2GND")
		(6 "In2.Cu" signal "L3")
		(8 "In3.Cu" signal "L4VCC")
		(10 "In4.Cu" signal "L5VCC")
		(12 "In5.Cu" signal "L6")
		(14 "In6.Cu" signal "L7GND")
		(2 "B.Cu" signal "BOTTOM")
		(9 "F.Adhes" user "F.Adhesive")
		(11 "B.Adhes" user "B.Adhesive")
		(13 "F.Paste" user "Package Geometry/Pastemask Top")
		(15 "B.Paste" user "Package Geometry/Pastemask Bottom")
		(5 "F.SilkS" user "Ref Des/Silkscreen Top")
		(7 "B.SilkS" user "Ref Des/Silkscreen Bottom")
		(1 "F.Mask" user "Board Geometry/Soldermask Top")
		(3 "B.Mask" user "Board Geometry/Soldermask Bottom")
		(17 "Dwgs.User" user "User.Drawings")
		(19 "Cmts.User" user "User.Comments")
		(21 "Eco1.User" user "User.Eco1")
		(23 "Eco2.User" user "User.Eco2")
		(25 "Edge.Cuts" user "Board Geometry/Outline")
		(27 "Margin" user)
		(31 "F.CrtYd" user "Package Geometry/Place Bound Top")
		(29 "B.CrtYd" user "Package Geometry/Place Bound Bottom")
		(35 "F.Fab" user "Ref Des/Assembly Top")
		(33 "B.Fab" user "Ref Des/Assembly Bottom")
	)
	(footprint ""
		(layer "B.Cu")
		(at 183.144668 -38.39845 -90)
		(property "Reference" "C475"
			(at 0 0 90)
			(layer "B.SilkS")
			(hide yes)
			(effects
				(font
					(size 1.27 1.27)
				)
				(justify mirror)
			)
		)
		(property "Value" "SCD1U6D3V1KX-GP"
			(at 2.8321 -1.7399 270)
			(unlocked yes)
			(layer "B.Fab")
			(hide yes)
			(effects
				(font
					(size 1.016 1.016)
					(thickness 0.1524)
				)
				(justify mirror)
			)
		)
		(property "Device Type" "C0201H13"
			(at 2.8321 -3.2639 270)
			(unlocked yes)
			(layer "B.Fab")
			(hide yes)
			(effects
				(font
					(size 1.016 1.016)
					(thickness 0.1524)
				)
				(justify mirror)
			)
		)
		(duplicate_pad_numbers_are_jumpers no)
		(fp_rect
			(start 0.2794 0.6477)
			(end -0.2794 -0.6477)
			(stroke
				(width 0)
				(type default)
			)
			(fill no)
			(layer "B.CrtYd")
		)
		(fp_rect
			(start 0.2794 0.6477)
			(end -0.2794 -0.6477)
			(stroke
				(width 0)
				(type default)
			)
			(fill no)
			(layer "B.Fab")
		)
		(pad "1" smd custom
			(at 0 -0.2794 90)
			(size 0.0762 0.0762)
			(layers "B.Cu" "B.Mask" "B.Paste")
			(net "P1V8_C")
			(options
				(clearance outline)
				(anchor circle)
			)
			(primitives
				(gr_poly
					(pts
						(arc
							(start 0.1524 0.127)
							(mid 0.137521 0.162921)
							(end 0.1016 0.1778)
						)
						(arc
							(start -0.1016 0.1778)
							(mid -0.137521 0.162921)
							(end -0.1524 0.127)
						)
						(arc
							(start -0.1524 -0.127)
							(mid -0.137521 -0.162921)
							(end -0.1016 -0.1778)
						)
						(arc
							(start 0.1016 -0.1778)
							(mid 0.137521 -0.162921)
							(end 0.1524 -0.127)
						)
					)
					(width 0)
					(fill yes)
				)
			)
		)
		(pad "2" smd custom
			(at 0 0.2794 90)
			(size 0.0762 0.0762)
			(layers "B.Cu" "B.Mask" "B.Paste")
			(net "GND")
			(options
				(clearance outline)
				(anchor circle)
			)
			(primitives
				(gr_poly
					(pts
						(arc
							(start 0.1524 0.127)
							(mid 0.137521 0.162921)
							(end 0.1016 0.1778)
						)
						(arc
							(start -0.1016 0.1778)
							(mid -0.137521 0.162921)
							(end -0.1524 0.127)
						)
						(arc
							(start -0.1524 -0.127)
							(mid -0.137521 -0.162921)
							(end -0.1016 -0.1778)
						)
						(arc
							(start 0.1016 -0.1778)
							(mid 0.137521 -0.162921)
							(end 0.1524 -0.127)
						)
					)
					(width 0)
					(fill yes)
				)
			)
		)
	)
	(footprint ""
		(layer "B.Cu")
		(at 167.344598 -49.481232 90)
		(property "Reference" "C463"
			(at 0 0 90)
			(layer "B.SilkS")
			(hide yes)
			(effects
				(font
					(size 1.27 1.27)
				)
				(justify mirror)
			)
		)
		(property "Value" "SCD1U6D3V1KX-GP"
			(at 2.8321 -1.7399 90)
			(unlocked yes)
			(layer "B.Fab")
			(hide yes)
			(effects
				(font
					(size 1.016 1.016)
					(thickness 0.1524)
				)
				(justify mirror)
			)
		)
		(property "Device Type" "C0201H13"
			(at 2.8321 -3.2639 90)
			(unlocked yes)
			(layer "B.Fab")
			(hide yes)
			(effects
				(font
					(size 1.016 1.016)
					(thickness 0.1524)
				)
				(justify mirror)
			)
		)
		(duplicate_pad_numbers_are_jumpers no)
		(fp_rect
			(start 0.2794 0.6477)
			(end -0.2794 -0.6477)
			(stroke
				(width 0)
				(type default)
			)
			(fill no)
			(layer "B.CrtYd")
		)
		(fp_rect
			(start 0.2794 0.6477)
			(end -0.2794 -0.6477)
			(stroke
				(width 0)
				(type default)
			)
			(fill no)
			(layer "B.Fab")
		)
		(pad "1" smd custom
			(at 0 -0.2794 270)
			(size 0.0762 0.0762)
			(layers "B.Cu" "B.Mask" "B.Paste")
			(net "P1V8_C")
			(options
				(clearance outline)
				(anchor circle)
			)
			(primitives
				(gr_poly
					(pts
						(arc
							(start 0.1524 0.127)
							(mid 0.137521 0.162921)
							(end 0.1016 0.1778)
						)
						(arc
							(start -0.1016 0.1778)
							(mid -0.137521 0.162921)
							(end -0.1524 0.127)
						)
						(arc
							(start -0.1524 -0.127)
							(mid -0.137521 -0.162921)
							(end -0.1016 -0.1778)
						)
						(arc
							(start 0.1016 -0.1778)
							(mid 0.137521 -0.162921)
							(end 0.1524 -0.127)
						)
					)
					(width 0)
					(fill yes)
				)
			)
		)
		(pad "2" smd custom
			(at 0 0.2794 270)
			(size 0.0762 0.0762)
			(layers "B.Cu" "B.Mask" "B.Paste")
			(net "GND")
			(options
				(clearance outline)
				(anchor circle)
			)
			(primitives
				(gr_poly
					(pts
						(arc
							(start 0.1524 0.127)
							(mid 0.137521 0.162921)
							(end 0.1016 0.1778)
						)
						(arc
							(start -0.1016 0.1778)
							(mid -0.137521 0.162921)
							(end -0.1524 0.127)
						)
						(arc
							(start -0.1524 -0.127)
							(mid -0.137521 -0.162921)
							(end -0.1016 -0.1778)
						)
						(arc
							(start 0.1016 -0.1778)
							(mid 0.137521 -0.162921)
							(end 0.1524 -0.127)
						)
					)
					(width 0)
					(fill yes)
				)
			)
		)
	)
	(footprint ""
		(layer "B.Cu")
		(at 124.5108 -57.7596 90)
		(property "Reference" "C278"
			(at 0 0 90)
			(layer "B.SilkS")
			(hide yes)
			(effects
				(font
					(size 1.27 1.27)
				)
				(justify mirror)
			)
		)
		(property "Value" "SCD1U6D3V1KX-GP"
			(at 2.8321 -1.7399 90)
			(unlocked yes)
			(layer "B.Fab")
			(hide yes)
			(effects
				(font
					(size 1.016 1.016)
					(thickness 0.1524)
				)
				(justify mirror)
			)
		)
		(property "Device Type" "C0201H13"
			(at 2.8321 -3.2639 90)
			(unlocked yes)
			(layer "B.Fab")
			(hide yes)
			(effects
				(font
					(size 1.016 1.016)
					(thickness 0.1524)
				)
				(justify mirror)
			)
		)
		(duplicate_pad_numbers_are_jumpers no)
		(fp_rect
			(start 0.2794 0.6477)
			(end -0.2794 -0.6477)
			(stroke
				(width 0)
				(type default)
			)
			(fill no)
			(layer "B.CrtYd")
		)
		(fp_rect
			(start 0.2794 0.6477)
			(end -0.2794 -0.6477)
			(stroke
				(width 0)
				(type default)
			)
			(fill no)
			(layer "B.Fab")
		)
		(pad "1" smd custom
			(at 0 -0.2794 270)
			(size 0.0762 0.0762)
			(layers "B.Cu" "B.Mask" "B.Paste")
			(net "GB_VDDA")
			(options
				(clearance outline)
				(anchor circle)
			)
			(primitives
				(gr_poly
					(pts
						(arc
							(start 0.1524 0.127)
							(mid 0.137521 0.162921)
							(end 0.1016 0.1778)
						)
						(arc
							(start -0.1016 0.1778)
							(mid -0.137521 0.162921)
							(end -0.1524 0.127)
						)
						(arc
							(start -0.1524 -0.127)
							(mid -0.137521 -0.162921)
							(end -0.1016 -0.1778)
						)
						(arc
							(start 0.1016 -0.1778)
							(mid 0.137521 -0.162921)
							(end 0.1524 -0.127)
						)
					)
					(width 0)
					(fill yes)
				)
			)
		)
		(pad "2" smd custom
			(at 0 0.2794 270)
			(size 0.0762 0.0762)
			(layers "B.Cu" "B.Mask" "B.Paste")
			(net "GND")
			(options
				(clearance outline)
				(anchor circle)
			)
			(primitives
				(gr_poly
					(pts
						(arc
							(start 0.1524 0.127)
							(mid 0.137521 0.162921)
							(end 0.1016 0.1778)
						)
						(arc
							(start -0.1016 0.1778)
							(mid -0.137521 0.162921)
							(end -0.1524 0.127)
						)
						(arc
							(start -0.1524 -0.127)
							(mid -0.137521 -0.162921)
							(end -0.1016 -0.1778)
						)
						(arc
							(start 0.1016 -0.1778)
							(mid 0.137521 -0.162921)
							(end 0.1524 -0.127)
						)
					)
					(width 0)
					(fill yes)
				)
			)
		)
	)
	(footprint ""
		(layer "B.Cu")
		(at 176.1998 -38.6715 90)
		(property "Reference" "C417"
			(at 0 0 90)
			(layer "B.SilkS")
			(hide yes)
			(effects
				(font
					(size 1.27 1.27)
				)
				(justify mirror)
			)
		)
		(property "Value" "SCD1U6D3V1KX-GP"
			(at 2.8321 -1.7399 90)
			(unlocked yes)
			(layer "B.Fab")
			(hide yes)
			(effects
				(font
					(size 1.016 1.016)
					(thickness 0.1524)
				)
				(justify mirror)
			)
		)
		(property "Device Type" "C0201H13"
			(at 2.8321 -3.2639 90)
			(unlocked yes)
			(layer "B.Fab")
			(hide yes)
			(effects
				(font
					(size 1.016 1.016)
					(thickness 0.1524)
				)
				(justify mirror)
			)
		)
		(duplicate_pad_numbers_are_jumpers no)
		(fp_rect
			(start 0.2794 0.6477)
			(end -0.2794 -0.6477)
			(stroke
				(width 0)
				(type default)
			)
			(fill no)
			(layer "B.CrtYd")
		)
		(fp_rect
			(start 0.2794 0.6477)
			(end -0.2794 -0.6477)
			(stroke
				(width 0)
				(type default)
			)
			(fill no)
			(layer "B.Fab")
		)
		(pad "1" smd custom
			(at 0 -0.2794 270)
			(size 0.0762 0.0762)
			(layers "B.Cu" "B.Mask" "B.Paste")
			(net "P0V975")
			(options
				(clearance outline)
				(anchor circle)
			)
			(primitives
				(gr_poly
					(pts
						(arc
							(start 0.1524 0.127)
							(mid 0.137521 0.162921)
							(end 0.1016 0.1778)
						)
						(arc
							(start -0.1016 0.1778)
							(mid -0.137521 0.162921)
							(end -0.1524 0.127)
						)
						(arc
							(start -0.1524 -0.127)
							(mid -0.137521 -0.162921)
							(end -0.1016 -0.1778)
						)
						(arc
							(start 0.1016 -0.1778)
							(mid 0.137521 -0.162921)
							(end 0.1524 -0.127)
						)
					)
					(width 0)
					(fill yes)
				)
			)
		)
		(pad "2" smd custom
			(at 0 0.2794 270)
			(size 0.0762 0.0762)
			(layers "B.Cu" "B.Mask" "B.Paste")
			(net "GND")
			(options
				(clearance outline)
				(anchor circle)
			)
			(primitives
				(gr_poly
					(pts
						(arc
							(start 0.1524 0.127)
							(mid 0.137521 0.162921)
							(end 0.1016 0.1778)
						)
						(arc
							(start -0.1016 0.1778)
							(mid -0.137521 0.162921)
							(end -0.1524 0.127)
						)
						(arc
							(start -0.1524 -0.127)
							(mid -0.137521 -0.162921)
							(end -0.1016 -0.1778)
						)
						(arc
							(start 0.1016 -0.1778)
							(mid 0.137521 -0.162921)
							(end 0.1524 -0.127)
						)
					)
					(width 0)
					(fill yes)
				)
			)
		)
	)
	(footprint ""
		(layer "B.Cu")
		(at 114.6683 -64.4779)
		(property "Reference" "C175"
			(at 0 0 0)
			(layer "B.SilkS")
			(hide yes)
			(effects
				(font
					(size 1.27 1.27)
				)
				(justify mirror)
			)
		)
		(property "Value" "SCD1U6D3V1KX-GP"
			(at 2.8321 -1.7399 0)
			(unlocked yes)
			(layer "B.Fab")
			(hide yes)
			(effects
				(font
					(size 1.016 1.016)
					(thickness 0.1524)
				)
				(justify mirror)
			)
		)
		(property "Device Type" "C0201H13"
			(at 2.8321 -3.2639 0)
			(unlocked yes)
			(layer "B.Fab")
			(hide yes)
			(effects
				(font
					(size 1.016 1.016)
					(thickness 0.1524)
				)
				(justify mirror)
			)
		)
		(duplicate_pad_numbers_are_jumpers no)
		(fp_rect
			(start 0.2794 0.6477)
			(end -0.2794 -0.6477)
			(stroke
				(width 0)
				(type default)
			)
			(fill no)
			(layer "B.CrtYd")
		)
		(fp_rect
			(start 0.2794 0.6477)
			(end -0.2794 -0.6477)
			(stroke
				(width 0)
				(type default)
			)
			(fill no)
			(layer "B.Fab")
		)
		(pad "1" smd custom
			(at 0 -0.2794 180)
			(size 0.0762 0.0762)
			(layers "B.Cu" "B.Mask" "B.Paste")
			(net "P0V9")
			(options
				(clearance outline)
				(anchor circle)
			)
			(primitives
				(gr_poly
					(pts
						(arc
							(start 0.1524 0.127)
							(mid 0.137521 0.162921)
							(end 0.1016 0.1778)
						)
						(arc
							(start -0.1016 0.1778)
							(mid -0.137521 0.162921)
							(end -0.1524 0.127)
						)
						(arc
							(start -0.1524 -0.127)
							(mid -0.137521 -0.162921)
							(end -0.1016 -0.1778)
						)
						(arc
							(start 0.1016 -0.1778)
							(mid 0.137521 -0.162921)
							(end 0.1524 -0.127)
						)
					)
					(width 0)
					(fill yes)
				)
			)
		)
		(pad "2" smd custom
			(at 0 0.2794 180)
			(size 0.0762 0.0762)
			(layers "B.Cu" "B.Mask" "B.Paste")
			(net "GND")
			(options
				(clearance outline)
				(anchor circle)
			)
			(primitives
				(gr_poly
					(pts
						(arc
							(start 0.1524 0.127)
							(mid 0.137521 0.162921)
							(end 0.1016 0.1778)
						)
						(arc
							(start -0.1016 0.1778)
							(mid -0.137521 0.162921)
							(end -0.1524 0.127)
						)
						(arc
							(start -0.1524 -0.127)
							(mid -0.137521 -0.162921)
							(end -0.1016 -0.1778)
						)
						(arc
							(start 0.1016 -0.1778)
							(mid 0.137521 -0.162921)
							(end 0.1524 -0.127)
						)
					)
					(width 0)
					(fill yes)
				)
			)
		)
	)
	(footprint ""
		(layer "B.Cu")
		(at 114.6048 -71.882)
		(property "Reference" "C127"
			(at 0 0 0)
			(layer "B.SilkS")
			(hide yes)
			(effects
				(font
					(size 1.27 1.27)
				)
				(justify mirror)
			)
		)
		(property "Value" "SC1KP25V1KX-GP"
			(at 2.8321 -1.7399 0)
			(unlocked yes)
			(layer "B.Fab")
			(hide yes)
			(effects
				(font
					(size 1.016 1.016)
					(thickness 0.1524)
				)
				(justify mirror)
			)
		)
		(property "Device Type" "C0201H13"
			(at 2.8321 -3.2639 0)
			(unlocked yes)
			(layer "B.Fab")
			(hide yes)
			(effects
				(font
					(size 1.016 1.016)
					(thickness 0.1524)
				)
				(justify mirror)
			)
		)
		(duplicate_pad_numbers_are_jumpers no)
		(fp_rect
			(start 0.2794 0.6477)
			(end -0.2794 -0.6477)
			(stroke
				(width 0)
				(type default)
			)
			(fill no)
			(layer "B.CrtYd")
		)
		(fp_rect
			(start 0.2794 0.6477)
			(end -0.2794 -0.6477)
			(stroke
				(width 0)
				(type default)
			)
			(fill no)
			(layer "B.Fab")
		)
		(pad "1" smd custom
			(at 0 -0.2794 180)
			(size 0.0762 0.0762)
			(layers "B.Cu" "B.Mask" "B.Paste")
			(net "P1V8_E")
			(options
				(clearance outline)
				(anchor circle)
			)
			(primitives
				(gr_poly
					(pts
						(arc
							(start 0.1524 0.127)
							(mid 0.137521 0.162921)
							(end 0.1016 0.1778)
						)
						(arc
							(start -0.1016 0.1778)
							(mid -0.137521 0.162921)
							(end -0.1524 0.127)
						)
						(arc
							(start -0.1524 -0.127)
							(mid -0.137521 -0.162921)
							(end -0.1016 -0.1778)
						)
						(arc
							(start 0.1016 -0.1778)
							(mid 0.137521 -0.162921)
							(end 0.1524 -0.127)
						)
					)
					(width 0)
					(fill yes)
				)
			)
		)
		(pad "2" smd custom
			(at 0 0.2794 180)
			(size 0.0762 0.0762)
			(layers "B.Cu" "B.Mask" "B.Paste")
			(net "GND")
			(options
				(clearance outline)
				(anchor circle)
			)
			(primitives
				(gr_poly
					(pts
						(arc
							(start 0.1524 0.127)
							(mid 0.137521 0.162921)
							(end 0.1016 0.1778)
						)
						(arc
							(start -0.1016 0.1778)
							(mid -0.137521 0.162921)
							(end -0.1524 0.127)
						)
						(arc
							(start -0.1524 -0.127)
							(mid -0.137521 -0.162921)
							(end -0.1016 -0.1778)
						)
						(arc
							(start 0.1016 -0.1778)
							(mid 0.137521 -0.162921)
							(end 0.1524 -0.127)
						)
					)
					(width 0)
					(fill yes)
				)
			)
		)
	)
	(footprint ""
		(layer "B.Cu")
		(at 137.4648 -67.7926 -90)
		(property "Reference" "C18"
			(at 0 0 90)
			(layer "B.SilkS")
			(hide yes)
			(effects
				(font
					(size 1.27 1.27)
				)
				(justify mirror)
			)
		)
		(property "Value" "SCD01U16V1KX-GP"
			(at 2.8321 -1.7399 270)
			(unlocked yes)
			(layer "B.Fab")
			(hide yes)
			(effects
				(font
					(size 1.016 1.016)
					(thickness 0.1524)
				)
				(justify mirror)
			)
		)
		(property "Device Type" "C0201H13"
			(at 2.8321 -3.2639 270)
			(unlocked yes)
			(layer "B.Fab")
			(hide yes)
			(effects
				(font
					(size 1.016 1.016)
					(thickness 0.1524)
				)
				(justify mirror)
			)
		)
		(duplicate_pad_numbers_are_jumpers no)
		(fp_rect
			(start 0.2794 0.6477)
			(end -0.2794 -0.6477)
			(stroke
				(width 0)
				(type default)
			)
			(fill no)
			(layer "B.CrtYd")
		)
		(fp_rect
			(start 0.2794 0.6477)
			(end -0.2794 -0.6477)
			(stroke
				(width 0)
				(type default)
			)
			(fill no)
			(layer "B.Fab")
		)
		(pad "1" smd custom
			(at 0 -0.2794 90)
			(size 0.0762 0.0762)
			(layers "B.Cu" "B.Mask" "B.Paste")
			(net "PHY_DPB_TO_SCC_3_DN")
			(options
				(clearance outline)
				(anchor circle)
			)
			(primitives
				(gr_poly
					(pts
						(arc
							(start 0.1524 0.127)
							(mid 0.137521 0.162921)
							(end 0.1016 0.1778)
						)
						(arc
							(start -0.1016 0.1778)
							(mid -0.137521 0.162921)
							(end -0.1524 0.127)
						)
						(arc
							(start -0.1524 -0.127)
							(mid -0.137521 -0.162921)
							(end -0.1016 -0.1778)
						)
						(arc
							(start 0.1016 -0.1778)
							(mid 0.137521 -0.162921)
							(end 0.1524 -0.127)
						)
					)
					(width 0)
					(fill yes)
				)
			)
		)
		(pad "2" smd custom
			(at 0 0.2794 90)
			(size 0.0762 0.0762)
			(layers "B.Cu" "B.Mask" "B.Paste")
			(net "PHY_DPB_TO_SCC_C_3_DN")
			(options
				(clearance outline)
				(anchor circle)
			)
			(primitives
				(gr_poly
					(pts
						(arc
							(start 0.1524 0.127)
							(mid 0.137521 0.162921)
							(end 0.1016 0.1778)
						)
						(arc
							(start -0.1016 0.1778)
							(mid -0.137521 0.162921)
							(end -0.1524 0.127)
						)
						(arc
							(start -0.1524 -0.127)
							(mid -0.137521 -0.162921)
							(end -0.1016 -0.1778)
						)
						(arc
							(start 0.1016 -0.1778)
							(mid 0.137521 -0.162921)
							(end 0.1524 -0.127)
						)
					)
					(width 0)
					(fill yes)
				)
			)
		)
	)
	(footprint ""
		(layer "B.Cu")
		(at 135.10768 -61.304678 180)
		(property "Reference" "C24"
			(at 0 0 0)
			(layer "B.SilkS")
			(hide yes)
			(effects
				(font
					(size 1.27 1.27)
				)
				(justify mirror)
			)
		)
		(property "Value" "SCD01U16V1KX-GP"
			(at 2.8321 -1.7399 180)
			(unlocked yes)
			(layer "B.Fab")
			(hide yes)
			(effects
				(font
					(size 1.016 1.016)
					(thickness 0.1524)
				)
				(justify mirror)
			)
		)
		(property "Device Type" "C0201H13"
			(at 2.8321 -3.2639 180)
			(unlocked yes)
			(layer "B.Fab")
			(hide yes)
			(effects
				(font
					(size 1.016 1.016)
					(thickness 0.1524)
				)
				(justify mirror)
			)
		)
		(duplicate_pad_numbers_are_jumpers no)
		(fp_rect
			(start 0.2794 0.6477)
			(end -0.2794 -0.6477)
			(stroke
				(width 0)
				(type default)
			)
			(fill no)
			(layer "B.CrtYd")
		)
		(fp_rect
			(start 0.2794 0.6477)
			(end -0.2794 -0.6477)
			(stroke
				(width 0)
				(type default)
			)
			(fill no)
			(layer "B.Fab")
		)
		(pad "1" smd custom
			(at 0 -0.2794)
			(size 0.0762 0.0762)
			(layers "B.Cu" "B.Mask" "B.Paste")
			(net "PHY_DPB_TO_SCC_0_DN")
			(options
				(clearance outline)
				(anchor circle)
			)
			(primitives
				(gr_poly
					(pts
						(arc
							(start 0.1524 0.127)
							(mid 0.137521 0.162921)
							(end 0.1016 0.1778)
						)
						(arc
							(start -0.1016 0.1778)
							(mid -0.137521 0.162921)
							(end -0.1524 0.127)
						)
						(arc
							(start -0.1524 -0.127)
							(mid -0.137521 -0.162921)
							(end -0.1016 -0.1778)
						)
						(arc
							(start 0.1016 -0.1778)
							(mid 0.137521 -0.162921)
							(end 0.1524 -0.127)
						)
					)
					(width 0)
					(fill yes)
				)
			)
		)
		(pad "2" smd custom
			(at 0 0.2794)
			(size 0.0762 0.0762)
			(layers "B.Cu" "B.Mask" "B.Paste")
			(net "PHY_DPB_TO_SCC_C_0_DN")
			(options
				(clearance outline)
				(anchor circle)
			)
			(primitives
				(gr_poly
					(pts
						(arc
							(start 0.1524 0.127)
							(mid 0.137521 0.162921)
							(end 0.1016 0.1778)
						)
						(arc
							(start -0.1016 0.1778)
							(mid -0.137521 0.162921)
							(end -0.1524 0.127)
						)
						(arc
							(start -0.1524 -0.127)
							(mid -0.137521 -0.162921)
							(end -0.1016 -0.1778)
						)
						(arc
							(start 0.1016 -0.1778)
							(mid 0.137521 -0.162921)
							(end 0.1524 -0.127)
						)
					)
					(width 0)
					(fill yes)
				)
			)
		)
	)
)
